(kicad_pcb
	(version 20260206)
	(generator "pcbnew")
	(generator_version "10.0")
	(general
		(thickness 1.6)
		(legacy_teardrops no)
	)
	(paper "A4")
	(title_block
		(title "01162023_DA0F0TEBIF0_F0T_Expander_BD_F_brd_V02_OCP.brd")
		(comment 1 "Grand Teton / footprints 3314-3321 of 9728")
	)
	(layers
		(0 "F.Cu" signal "TOP")
		(4 "In1.Cu" signal "GND")
		(6 "In2.Cu" signal "VCC")
		(8 "In3.Cu" signal "VCC1")
		(10 "In4.Cu" signal "GND1")
		(12 "In5.Cu" signal "IN1")
		(14 "In6.Cu" signal "GND2")
		(16 "In7.Cu" signal "IN2")
		(18 "In8.Cu" signal "GND3")
		(20 "In9.Cu" signal "IN3")
		(22 "In10.Cu" signal "GND4")
		(24 "In11.Cu" signal "IN4")
		(26 "In12.Cu" signal "GND5")
		(28 "In13.Cu" signal "IN5")
		(30 "In14.Cu" signal "GND6")
		(32 "In15.Cu" signal "IN6")
		(34 "In16.Cu" signal "GND7")
		(2 "B.Cu" signal "BOTTOM")
		(9 "F.Adhes" user "F.Adhesive")
		(11 "B.Adhes" user "B.Adhesive")
		(13 "F.Paste" user "Package Geometry/Pastemask Top")
		(15 "B.Paste" user "Package Geometry/Pastemask Bottom")
		(5 "F.SilkS" user "Ref Des/Silkscreen Top")
		(7 "B.SilkS" user "Ref Des/Silkscreen Bottom")
		(1 "F.Mask" user "Board Geometry/Soldermask Top")
		(3 "B.Mask" user "Board Geometry/Soldermask Bottom")
		(17 "Dwgs.User" user "User.Drawings")
		(19 "Cmts.User" user "User.Comments")
		(21 "Eco1.User" user "User.Eco1")
		(23 "Eco2.User" user "User.Eco2")
		(25 "Edge.Cuts" user "Board Geometry/Outline")
		(27 "Margin" user)
		(31 "F.CrtYd" user "Package Geometry/Place Bound Top")
		(29 "B.CrtYd" user "Package Geometry/Place Bound Bottom")
		(35 "F.Fab" user "Ref Des/Assembly Top")
		(33 "B.Fab" user "Ref Des/Assembly Bottom")
	)
	(footprint ""
		(layer "F.Cu")
		(at 398.782032 -38.041072 180)
		(property "Reference" "R6120"
			(at 0 0 180)
			(layer "F.SilkS")
			(hide yes)
			(effects
				(font
					(size 1.27 1.27)
				)
			)
		)
		(property "Value" ""
			(at 0 0 180)
			(layer "F.Fab")
			(effects
				(font
					(size 1.27 1.27)
				)
			)
		)
		(duplicate_pad_numbers_are_jumpers no)
		(fp_line
			(start 0.7874 0.4064)
			(end -0.7874 0.4064)
			(stroke
				(width 0.1524)
				(type default)
			)
			(layer "F.SilkS")
		)
		(fp_line
			(start 0.7874 -0.4064)
			(end 0.7874 0.4064)
			(stroke
				(width 0.1524)
				(type default)
			)
			(layer "F.SilkS")
		)
		(fp_line
			(start -0.7874 0.4064)
			(end -0.7874 -0.4064)
			(stroke
				(width 0.1524)
				(type default)
			)
			(layer "F.SilkS")
		)
		(fp_line
			(start -0.7874 -0.4064)
			(end 0.7874 -0.4064)
			(stroke
				(width 0.1524)
				(type default)
			)
			(layer "F.SilkS")
		)
		(fp_line
			(start 0.67945 0.3048)
			(end 0.120396 0.3048)
			(stroke
				(width 0.1)
				(type default)
			)
			(layer "F.Fab")
		)
		(fp_line
			(start 0.67945 -0.3048)
			(end 0.67945 0.3048)
			(stroke
				(width 0.1)
				(type default)
			)
			(layer "F.Fab")
		)
		(fp_line
			(start 0.12065 -0.2794)
			(end 0.12065 -0.3048)
			(stroke
				(width 0.1)
				(type default)
			)
			(layer "F.Fab")
		)
		(fp_line
			(start 0.12065 -0.3048)
			(end 0.67945 -0.3048)
			(stroke
				(width 0.1)
				(type default)
			)
			(layer "F.Fab")
		)
		(fp_line
			(start 0.120396 0.3048)
			(end 0.120396 0.2794)
			(stroke
				(width 0.1)
				(type default)
			)
			(layer "F.Fab")
		)
		(fp_line
			(start 0.120396 0.2794)
			(end -0.12065 0.2794)
			(stroke
				(width 0.1)
				(type default)
			)
			(layer "F.Fab")
		)
		(fp_line
			(start -0.12065 0.3048)
			(end -0.67945 0.3048)
			(stroke
				(width 0.1)
				(type default)
			)
			(layer "F.Fab")
		)
		(fp_line
			(start -0.12065 0.2794)
			(end -0.12065 0.3048)
			(stroke
				(width 0.1)
				(type default)
			)
			(layer "F.Fab")
		)
		(fp_line
			(start -0.12065 -0.2794)
			(end 0.12065 -0.2794)
			(stroke
				(width 0.1)
				(type default)
			)
			(layer "F.Fab")
		)
		(fp_line
			(start -0.12065 -0.305054)
			(end -0.12065 -0.2794)
			(stroke
				(width 0.1)
				(type default)
			)
			(layer "F.Fab")
		)
		(fp_line
			(start -0.67945 0.3048)
			(end -0.67945 -0.305054)
			(stroke
				(width 0.1)
				(type default)
			)
			(layer "F.Fab")
		)
		(fp_line
			(start -0.67945 -0.305054)
			(end -0.12065 -0.305054)
			(stroke
				(width 0.1)
				(type default)
			)
			(layer "F.Fab")
		)
		(pad "1" smd circle
			(at -0.40005 0 180)
			(size 0 0)
			(layers "F.Cu" "F.Mask" "F.Paste")
			(net "P5V_AUX")
		)
		(pad "2" smd circle
			(at 0.40005 0 180)
			(size 0 0)
			(layers "F.Cu" "F.Mask" "F.Paste")
			(net "P3V3_SSD14_PG_G2")
		)
	)
	(footprint ""
		(layer "F.Cu")
		(at 54.875176 -63.086234)
		(property "Reference" "R5852"
			(at 0 0 0)
			(layer "F.SilkS")
			(hide yes)
			(effects
				(font
					(size 1.27 1.27)
				)
			)
		)
		(property "Value" ""
			(at 0 0 0)
			(layer "F.Fab")
			(effects
				(font
					(size 1.27 1.27)
				)
			)
		)
		(duplicate_pad_numbers_are_jumpers no)
		(fp_line
			(start -0.7874 -0.4064)
			(end 0.7874 -0.4064)
			(stroke
				(width 0.1524)
				(type default)
			)
			(layer "F.SilkS")
		)
		(fp_line
			(start -0.7874 0.4064)
			(end -0.7874 -0.4064)
			(stroke
				(width 0.1524)
				(type default)
			)
			(layer "F.SilkS")
		)
		(fp_line
			(start 0.7874 -0.4064)
			(end 0.7874 0.4064)
			(stroke
				(width 0.1524)
				(type default)
			)
			(layer "F.SilkS")
		)
		(fp_line
			(start 0.7874 0.4064)
			(end -0.7874 0.4064)
			(stroke
				(width 0.1524)
				(type default)
			)
			(layer "F.SilkS")
		)
		(fp_line
			(start -0.67945 -0.305054)
			(end -0.12065 -0.305054)
			(stroke
				(width 0.1)
				(type default)
			)
			(layer "F.Fab")
		)
		(fp_line
			(start -0.67945 0.3048)
			(end -0.67945 -0.305054)
			(stroke
				(width 0.1)
				(type default)
			)
			(layer "F.Fab")
		)
		(fp_line
			(start -0.12065 -0.305054)
			(end -0.12065 -0.2794)
			(stroke
				(width 0.1)
				(type default)
			)
			(layer "F.Fab")
		)
		(fp_line
			(start -0.12065 -0.2794)
			(end 0.12065 -0.2794)
			(stroke
				(width 0.1)
				(type default)
			)
			(layer "F.Fab")
		)
		(fp_line
			(start -0.12065 0.2794)
			(end -0.12065 0.3048)
			(stroke
				(width 0.1)
				(type default)
			)
			(layer "F.Fab")
		)
		(fp_line
			(start -0.12065 0.3048)
			(end -0.67945 0.3048)
			(stroke
				(width 0.1)
				(type default)
			)
			(layer "F.Fab")
		)
		(fp_line
			(start 0.120396 0.2794)
			(end -0.12065 0.2794)
			(stroke
				(width 0.1)
				(type default)
			)
			(layer "F.Fab")
		)
		(fp_line
			(start 0.120396 0.3048)
			(end 0.120396 0.2794)
			(stroke
				(width 0.1)
				(type default)
			)
			(layer "F.Fab")
		)
		(fp_line
			(start 0.12065 -0.3048)
			(end 0.67945 -0.3048)
			(stroke
				(width 0.1)
				(type default)
			)
			(layer "F.Fab")
		)
		(fp_line
			(start 0.12065 -0.2794)
			(end 0.12065 -0.3048)
			(stroke
				(width 0.1)
				(type default)
			)
			(layer "F.Fab")
		)
		(fp_line
			(start 0.67945 -0.3048)
			(end 0.67945 0.3048)
			(stroke
				(width 0.1)
				(type default)
			)
			(layer "F.Fab")
		)
		(fp_line
			(start 0.67945 0.3048)
			(end 0.120396 0.3048)
			(stroke
				(width 0.1)
				(type default)
			)
			(layer "F.Fab")
		)
		(pad "1" smd circle
			(at -0.40005 0)
			(size 0 0)
			(layers "F.Cu" "F.Mask" "F.Paste")
			(net "P12V_SSD2_R")
		)
		(pad "2" smd circle
			(at 0.40005 0)
			(size 0 0)
			(layers "F.Cu" "F.Mask" "F.Paste")
			(net "P12V_SSD2_PG_G1")
		)
	)
	(footprint ""
		(layer "F.Cu")
		(at 161.358072 -72.766682 90)
		(property "Reference" "PC842"
			(at 0 0 90)
			(layer "F.SilkS")
			(hide yes)
			(effects
				(font
					(size 1.27 1.27)
				)
			)
		)
		(property "Value" ""
			(at 0 0 90)
			(layer "F.Fab")
			(effects
				(font
					(size 1.27 1.27)
				)
			)
		)
		(duplicate_pad_numbers_are_jumpers no)
		(fp_line
			(start 0.7874 -0.4064)
			(end 0.7874 0.4064)
			(stroke
				(width 0.1524)
				(type default)
			)
			(layer "F.SilkS")
		)
		(fp_line
			(start -0.7874 -0.4064)
			(end 0.7874 -0.4064)
			(stroke
				(width 0.1524)
				(type default)
			)
			(layer "F.SilkS")
		)
		(fp_line
			(start 0.7874 0.4064)
			(end -0.7874 0.4064)
			(stroke
				(width 0.1524)
				(type default)
			)
			(layer "F.SilkS")
		)
		(fp_line
			(start -0.7874 0.4064)
			(end -0.7874 -0.4064)
			(stroke
				(width 0.1524)
				(type default)
			)
			(layer "F.SilkS")
		)
		(fp_line
			(start -0.12065 -0.305054)
			(end -0.12065 -0.2794)
			(stroke
				(width 0.1)
				(type default)
			)
			(layer "F.Fab")
		)
		(fp_line
			(start -0.67945 -0.305054)
			(end -0.12065 -0.305054)
			(stroke
				(width 0.1)
				(type default)
			)
			(layer "F.Fab")
		)
		(fp_line
			(start 0.67945 -0.3048)
			(end 0.67945 0.3048)
			(stroke
				(width 0.1)
				(type default)
			)
			(layer "F.Fab")
		)
		(fp_line
			(start 0.12065 -0.3048)
			(end 0.67945 -0.3048)
			(stroke
				(width 0.1)
				(type default)
			)
			(layer "F.Fab")
		)
		(fp_line
			(start 0.12065 -0.2794)
			(end 0.12065 -0.3048)
			(stroke
				(width 0.1)
				(type default)
			)
			(layer "F.Fab")
		)
		(fp_line
			(start -0.12065 -0.2794)
			(end 0.12065 -0.2794)
			(stroke
				(width 0.1)
				(type default)
			)
			(layer "F.Fab")
		)
		(fp_line
			(start 0.120396 0.2794)
			(end -0.12065 0.2794)
			(stroke
				(width 0.1)
				(type default)
			)
			(layer "F.Fab")
		)
		(fp_line
			(start -0.12065 0.2794)
			(end -0.12065 0.3048)
			(stroke
				(width 0.1)
				(type default)
			)
			(layer "F.Fab")
		)
		(fp_line
			(start 0.67945 0.3048)
			(end 0.120396 0.3048)
			(stroke
				(width 0.1)
				(type default)
			)
			(layer "F.Fab")
		)
		(fp_line
			(start 0.120396 0.3048)
			(end 0.120396 0.2794)
			(stroke
				(width 0.1)
				(type default)
			)
			(layer "F.Fab")
		)
		(fp_line
			(start -0.12065 0.3048)
			(end -0.67945 0.3048)
			(stroke
				(width 0.1)
				(type default)
			)
			(layer "F.Fab")
		)
		(fp_line
			(start -0.67945 0.3048)
			(end -0.67945 -0.305054)
			(stroke
				(width 0.1)
				(type default)
			)
			(layer "F.Fab")
		)
		(pad "1" smd circle
			(at -0.40005 0 90)
			(size 0 0)
			(layers "F.Cu" "F.Mask" "F.Paste")
			(net "P12V_SSD5_CO_MODE")
		)
		(pad "2" smd circle
			(at 0.40005 0 90)
			(size 0 0)
			(layers "F.Cu" "F.Mask" "F.Paste")
			(net "GND")
		)
	)
	(footprint ""
		(layer "F.Cu")
		(at 152.738328 -105.609898)
		(property "Reference" "C269"
			(at 0 0 0)
			(layer "F.SilkS")
			(hide yes)
			(effects
				(font
					(size 1.27 1.27)
				)
			)
		)
		(property "Value" ""
			(at 0 0 0)
			(layer "F.Fab")
			(effects
				(font
					(size 1.27 1.27)
				)
			)
		)
		(duplicate_pad_numbers_are_jumpers no)
		(fp_line
			(start -0.299974 -0.150114)
			(end 0.299974 -0.150114)
			(stroke
				(width 0.1)
				(type default)
			)
			(layer "F.Fab")
		)
		(fp_line
			(start -0.299974 0.150114)
			(end -0.299974 -0.150114)
			(stroke
				(width 0.1)
				(type default)
			)
			(layer "F.Fab")
		)
		(fp_line
			(start 0.299974 -0.150114)
			(end 0.299974 0.150114)
			(stroke
				(width 0.1)
				(type default)
			)
			(layer "F.Fab")
		)
		(fp_line
			(start 0.299974 0.150114)
			(end -0.299974 0.150114)
			(stroke
				(width 0.1)
				(type default)
			)
			(layer "F.Fab")
		)
		(pad "1" smd rect
			(at -0.2667 0)
			(size 0.3048 0.381)
			(layers "F.Cu" "F.Mask" "F.Paste")
			(net "P5E_PEX1_STN1_TX_DP<19>")
		)
		(pad "2" smd rect
			(at 0.2667 0)
			(size 0.3048 0.381)
			(layers "F.Cu" "F.Mask" "F.Paste")
			(net "P5E_PEX1_STN1_TX_C_DP<19>")
		)
	)
	(footprint ""
		(layer "F.Cu")
		(at 113.561114 -260.671564)
		(property "Reference" "PR91"
			(at 0 0 0)
			(layer "F.SilkS")
			(hide yes)
			(effects
				(font
					(size 1.27 1.27)
				)
			)
		)
		(property "Value" ""
			(at 0 0 0)
			(layer "F.Fab")
			(effects
				(font
					(size 1.27 1.27)
				)
			)
		)
		(duplicate_pad_numbers_are_jumpers no)
		(fp_line
			(start -0.7874 -0.4064)
			(end 0.7874 -0.4064)
			(stroke
				(width 0.1524)
				(type default)
			)
			(layer "F.SilkS")
		)
		(fp_line
			(start -0.7874 0.4064)
			(end -0.7874 -0.4064)
			(stroke
				(width 0.1524)
				(type default)
			)
			(layer "F.SilkS")
		)
		(fp_line
			(start 0.7874 -0.4064)
			(end 0.7874 0.4064)
			(stroke
				(width 0.1524)
				(type default)
			)
			(layer "F.SilkS")
		)
		(fp_line
			(start 0.7874 0.4064)
			(end -0.7874 0.4064)
			(stroke
				(width 0.1524)
				(type default)
			)
			(layer "F.SilkS")
		)
		(fp_line
			(start -0.67945 -0.305054)
			(end -0.12065 -0.305054)
			(stroke
				(width 0.1)
				(type default)
			)
			(layer "F.Fab")
		)
		(fp_line
			(start -0.67945 0.3048)
			(end -0.67945 -0.305054)
			(stroke
				(width 0.1)
				(type default)
			)
			(layer "F.Fab")
		)
		(fp_line
			(start -0.12065 -0.305054)
			(end -0.12065 -0.2794)
			(stroke
				(width 0.1)
				(type default)
			)
			(layer "F.Fab")
		)
		(fp_line
			(start -0.12065 -0.2794)
			(end 0.12065 -0.2794)
			(stroke
				(width 0.1)
				(type default)
			)
			(layer "F.Fab")
		)
		(fp_line
			(start -0.12065 0.2794)
			(end -0.12065 0.3048)
			(stroke
				(width 0.1)
				(type default)
			)
			(layer "F.Fab")
		)
		(fp_line
			(start -0.12065 0.3048)
			(end -0.67945 0.3048)
			(stroke
				(width 0.1)
				(type default)
			)
			(layer "F.Fab")
		)
		(fp_line
			(start 0.120396 0.2794)
			(end -0.12065 0.2794)
			(stroke
				(width 0.1)
				(type default)
			)
			(layer "F.Fab")
		)
		(fp_line
			(start 0.120396 0.3048)
			(end 0.120396 0.2794)
			(stroke
				(width 0.1)
				(type default)
			)
			(layer "F.Fab")
		)
		(fp_line
			(start 0.12065 -0.3048)
			(end 0.67945 -0.3048)
			(stroke
				(width 0.1)
				(type default)
			)
			(layer "F.Fab")
		)
		(fp_line
			(start 0.12065 -0.2794)
			(end 0.12065 -0.3048)
			(stroke
				(width 0.1)
				(type default)
			)
			(layer "F.Fab")
		)
		(fp_line
			(start 0.67945 -0.3048)
			(end 0.67945 0.3048)
			(stroke
				(width 0.1)
				(type default)
			)
			(layer "F.Fab")
		)
		(fp_line
			(start 0.67945 0.3048)
			(end 0.120396 0.3048)
			(stroke
				(width 0.1)
				(type default)
			)
			(layer "F.Fab")
		)
		(pad "1" smd circle
			(at -0.40005 0)
			(size 0 0)
			(layers "F.Cu" "F.Mask" "F.Paste")
			(net "P0V8_PEX0_VREF")
		)
		(pad "2" smd circle
			(at 0.40005 0)
			(size 0 0)
			(layers "F.Cu" "F.Mask" "F.Paste")
			(net "P0V8_PEX0_ADDR")
		)
	)
	(footprint ""
		(layer "F.Cu")
		(at 152.738328 -104.695498)
		(property "Reference" "C268"
			(at 0 0 0)
			(layer "F.SilkS")
			(hide yes)
			(effects
				(font
					(size 1.27 1.27)
				)
			)
		)
		(property "Value" ""
			(at 0 0 0)
			(layer "F.Fab")
			(effects
				(font
					(size 1.27 1.27)
				)
			)
		)
		(duplicate_pad_numbers_are_jumpers no)
		(fp_line
			(start -0.299974 -0.150114)
			(end 0.299974 -0.150114)
			(stroke
				(width 0.1)
				(type default)
			)
			(layer "F.Fab")
		)
		(fp_line
			(start -0.299974 0.150114)
			(end -0.299974 -0.150114)
			(stroke
				(width 0.1)
				(type default)
			)
			(layer "F.Fab")
		)
		(fp_line
			(start 0.299974 -0.150114)
			(end 0.299974 0.150114)
			(stroke
				(width 0.1)
				(type default)
			)
			(layer "F.Fab")
		)
		(fp_line
			(start 0.299974 0.150114)
			(end -0.299974 0.150114)
			(stroke
				(width 0.1)
				(type default)
			)
			(layer "F.Fab")
		)
		(pad "1" smd rect
			(at -0.2667 0)
			(size 0.3048 0.381)
			(layers "F.Cu" "F.Mask" "F.Paste")
			(net "P5E_PEX1_STN1_TX_DN<19>")
		)
		(pad "2" smd rect
			(at 0.2667 0)
			(size 0.3048 0.381)
			(layers "F.Cu" "F.Mask" "F.Paste")
			(net "P5E_PEX1_STN1_TX_C_DN<19>")
		)
	)
	(footprint ""
		(layer "F.Cu")
		(at 312.21934 -122.270266 180)
		(property "Reference" "C450"
			(at 0 0 180)
			(layer "F.SilkS")
			(hide yes)
			(effects
				(font
					(size 1.27 1.27)
				)
			)
		)
		(property "Value" ""
			(at 0 0 180)
			(layer "F.Fab")
			(effects
				(font
					(size 1.27 1.27)
				)
			)
		)
		(duplicate_pad_numbers_are_jumpers no)
		(fp_line
			(start 0.299974 0.150114)
			(end -0.299974 0.150114)
			(stroke
				(width 0.1)
				(type default)
			)
			(layer "F.Fab")
		)
		(fp_line
			(start 0.299974 -0.150114)
			(end 0.299974 0.150114)
			(stroke
				(width 0.1)
				(type default)
			)
			(layer "F.Fab")
		)
		(fp_line
			(start -0.299974 0.150114)
			(end -0.299974 -0.150114)
			(stroke
				(width 0.1)
				(type default)
			)
			(layer "F.Fab")
		)
		(fp_line
			(start -0.299974 -0.150114)
			(end 0.299974 -0.150114)
			(stroke
				(width 0.1)
				(type default)
			)
			(layer "F.Fab")
		)
		(pad "1" smd rect
			(at -0.2667 0 180)
			(size 0.3048 0.381)
			(layers "F.Cu" "F.Mask" "F.Paste")
			(net "P5E_PEX2_STN0_TX_DN<2>")
		)
		(pad "2" smd rect
			(at 0.2667 0 180)
			(size 0.3048 0.381)
			(layers "F.Cu" "F.Mask" "F.Paste")
			(net "P5E_PEX2_STN0_TX_C_DN<2>")
		)
	)
	(footprint ""
		(layer "F.Cu")
		(at 263.494012 -35.264852)
		(property "Reference" "R5684"
			(at 0 0 0)
			(layer "F.SilkS")
			(hide yes)
			(effects
				(font
					(size 1.27 1.27)
				)
			)
		)
		(property "Value" ""
			(at 0 0 0)
			(layer "F.Fab")
			(effects
				(font
					(size 1.27 1.27)
				)
			)
		)
		(duplicate_pad_numbers_are_jumpers no)
		(fp_line
			(start -0.7874 -0.4064)
			(end 0.7874 -0.4064)
			(stroke
				(width 0.1524)
				(type default)
			)
			(layer "F.SilkS")
		)
		(fp_line
			(start -0.7874 0.4064)
			(end -0.7874 -0.4064)
			(stroke
				(width 0.1524)
				(type default)
			)
			(layer "F.SilkS")
		)
		(fp_line
			(start 0.7874 -0.4064)
			(end 0.7874 0.4064)
			(stroke
				(width 0.1524)
				(type default)
			)
			(layer "F.SilkS")
		)
		(fp_line
			(start 0.7874 0.4064)
			(end -0.7874 0.4064)
			(stroke
				(width 0.1524)
				(type default)
			)
			(layer "F.SilkS")
		)
		(fp_line
			(start -0.67945 -0.305054)
			(end -0.12065 -0.305054)
			(stroke
				(width 0.1)
				(type default)
			)
			(layer "F.Fab")
		)
		(fp_line
			(start -0.67945 0.3048)
			(end -0.67945 -0.305054)
			(stroke
				(width 0.1)
				(type default)
			)
			(layer "F.Fab")
		)
		(fp_line
			(start -0.12065 -0.305054)
			(end -0.12065 -0.2794)
			(stroke
				(width 0.1)
				(type default)
			)
			(layer "F.Fab")
		)
		(fp_line
			(start -0.12065 -0.2794)
			(end 0.12065 -0.2794)
			(stroke
				(width 0.1)
				(type default)
			)
			(layer "F.Fab")
		)
		(fp_line
			(start -0.12065 0.2794)
			(end -0.12065 0.3048)
			(stroke
				(width 0.1)
				(type default)
			)
			(layer "F.Fab")
		)
		(fp_line
			(start -0.12065 0.3048)
			(end -0.67945 0.3048)
			(stroke
				(width 0.1)
				(type default)
			)
			(layer "F.Fab")
		)
		(fp_line
			(start 0.120396 0.2794)
			(end -0.12065 0.2794)
			(stroke
				(width 0.1)
				(type default)
			)
			(layer "F.Fab")
		)
		(fp_line
			(start 0.120396 0.3048)
			(end 0.120396 0.2794)
			(stroke
				(width 0.1)
				(type default)
			)
			(layer "F.Fab")
		)
		(fp_line
			(start 0.12065 -0.3048)
			(end 0.67945 -0.3048)
			(stroke
				(width 0.1)
				(type default)
			)
			(layer "F.Fab")
		)
		(fp_line
			(start 0.12065 -0.2794)
			(end 0.12065 -0.3048)
			(stroke
				(width 0.1)
				(type default)
			)
			(layer "F.Fab")
		)
		(fp_line
			(start 0.67945 -0.3048)
			(end 0.67945 0.3048)
			(stroke
				(width 0.1)
				(type default)
			)
			(layer "F.Fab")
		)
		(fp_line
			(start 0.67945 0.3048)
			(end 0.120396 0.3048)
			(stroke
				(width 0.1)
				(type default)
			)
			(layer "F.Fab")
		)
		(pad "1" smd circle
			(at -0.40005 0)
			(size 0 0)
			(layers "F.Cu" "F.Mask" "F.Paste")
			(net "RST_SMB_SSD9_ISO_N")
		)
		(pad "2" smd circle
			(at 0.40005 0)
			(size 0 0)
			(layers "F.Cu" "F.Mask" "F.Paste")
			(net "GND")
		)
	)
)
